# S9S_MB_2U (Grand Teton) — schematic netlist excerpt (pin names and nets, part order shuffled) for the footprints in the layout excerpt that follows; sources: Cadence DE-HDL packaged netlist, KiCad conversion of 03242023_DA0F0TMBIJ0_F0T_Motherboard_J_brd_V01_OCP.brd

R4450  Q_RES  0 5% EMPTY  pkg 0402LF  page 196 : A = P3V3_AUX ; B = P3V3_AUX_USB_HUB_2
R1486  Q_RES  200 1% EMPTY  pkg 0402LF  page 182 : A = PVNN_TERM_CPU0 ; B = FM_PCH_TRIGGER1_R_N

(kicad_pcb
	(version 20260206)
	(generator "pcbnew")
	(generator_version "10.0")
	(general
		(thickness 1.6)
		(legacy_teardrops no)
	)
	(paper "A4")
	(title_block
		(title "03242023_DA0F0TMBIJ0_F0T_Motherboard_J_brd_V01_OCP.brd")
		(comment 1 "Grand Teton / footprints 6078-6080 of 6105")
	)
	(layers
		(0 "F.Cu" signal "TOP")
		(4 "In1.Cu" signal "GND")
		(6 "In2.Cu" signal "IN1")
		(8 "In3.Cu" signal "GND1")
		(10 "In4.Cu" signal "IN2")
		(12 "In5.Cu" signal "GND2")
		(14 "In6.Cu" signal "IN3")
		(16 "In7.Cu" signal "GND3")
		(18 "In8.Cu" signal "VCC")
		(20 "In9.Cu" signal "VCC1")
		(22 "In10.Cu" signal "GND4")
		(24 "In11.Cu" signal "IN4")
		(26 "In12.Cu" signal "GND5")
		(28 "In13.Cu" signal "IN5")
		(30 "In14.Cu" signal "GND6")
		(32 "In15.Cu" signal "IN6")
		(34 "In16.Cu" signal "GND7")
		(2 "B.Cu" signal "BOTTOM")
		(9 "F.Adhes" user "F.Adhesive")
		(11 "B.Adhes" user "B.Adhesive")
		(13 "F.Paste" user "Package Geometry/Pastemask Top")
		(15 "B.Paste" user "Package Geometry/Pastemask Bottom")
		(5 "F.SilkS" user "Ref Des/Silkscreen Top")
		(7 "B.SilkS" user "Ref Des/Silkscreen Bottom")
		(1 "F.Mask" user "Board Geometry/Soldermask Top")
		(3 "B.Mask" user "Board Geometry/Soldermask Bottom")
		(17 "Dwgs.User" user "User.Drawings")
		(19 "Cmts.User" user "User.Comments")
		(21 "Eco1.User" user "User.Eco1")
		(23 "Eco2.User" user "User.Eco2")
		(25 "Edge.Cuts" user "Board Geometry/Outline")
		(27 "Margin" user)
		(31 "F.CrtYd" user "Package Geometry/Place Bound Top")
		(29 "B.CrtYd" user "Package Geometry/Place Bound Bottom")
		(35 "F.Fab" user "Ref Des/Assembly Top")
		(33 "B.Fab" user "Ref Des/Assembly Bottom")
	)
	(footprint ""
		(layer "B.Cu")
		(at 315.11748 -56.276748 180)
		(property "Reference" "R1486"
			(at 0 0 0)
			(layer "B.SilkS")
			(hide yes)
			(effects
				(font
					(size 1.27 1.27)
				)
				(justify mirror)
			)
		)
		(property "Value" ""
			(at 0 0 0)
			(layer "B.Fab")
			(effects
				(font
					(size 1.27 1.27)
				)
				(justify mirror)
			)
		)
		(duplicate_pad_numbers_are_jumpers no)
		(fp_line
			(start 0.7874 0.4064)
			(end 0.7874 -0.4064)
			(stroke
				(width 0.1524)
				(type default)
			)
			(layer "B.SilkS")
		)
		(fp_line
			(start 0.7874 -0.4064)
			(end -0.7874 -0.4064)
			(stroke
				(width 0.1524)
				(type default)
			)
			(layer "B.SilkS")
		)
		(fp_line
			(start -0.7874 0.4064)
			(end 0.7874 0.4064)
			(stroke
				(width 0.1524)
				(type default)
			)
			(layer "B.SilkS")
		)
		(fp_line
			(start -0.7874 -0.4064)
			(end -0.7874 0.4064)
			(stroke
				(width 0.1524)
				(type default)
			)
			(layer "B.SilkS")
		)
		(fp_line
			(start 0.67945 0.3048)
			(end 0.67945 -0.305054)
			(stroke
				(width 0.1)
				(type default)
			)
			(layer "B.Fab")
		)
		(fp_line
			(start 0.67945 -0.305054)
			(end 0.12065 -0.305054)
			(stroke
				(width 0.1)
				(type default)
			)
			(layer "B.Fab")
		)
		(fp_line
			(start 0.12065 0.3048)
			(end 0.67945 0.3048)
			(stroke
				(width 0.1)
				(type default)
			)
			(layer "B.Fab")
		)
		(fp_line
			(start 0.12065 0.2794)
			(end 0.12065 0.3048)
			(stroke
				(width 0.1)
				(type default)
			)
			(layer "B.Fab")
		)
		(fp_line
			(start 0.12065 -0.2794)
			(end -0.12065 -0.2794)
			(stroke
				(width 0.1)
				(type default)
			)
			(layer "B.Fab")
		)
		(fp_line
			(start 0.12065 -0.305054)
			(end 0.12065 -0.2794)
			(stroke
				(width 0.1)
				(type default)
			)
			(layer "B.Fab")
		)
		(fp_line
			(start -0.120396 0.3048)
			(end -0.120396 0.2794)
			(stroke
				(width 0.1)
				(type default)
			)
			(layer "B.Fab")
		)
		(fp_line
			(start -0.120396 0.2794)
			(end 0.12065 0.2794)
			(stroke
				(width 0.1)
				(type default)
			)
			(layer "B.Fab")
		)
		(fp_line
			(start -0.12065 -0.2794)
			(end -0.12065 -0.3048)
			(stroke
				(width 0.1)
				(type default)
			)
			(layer "B.Fab")
		)
		(fp_line
			(start -0.12065 -0.3048)
			(end -0.67945 -0.3048)
			(stroke
				(width 0.1)
				(type default)
			)
			(layer "B.Fab")
		)
		(fp_line
			(start -0.67945 0.3048)
			(end -0.120396 0.3048)
			(stroke
				(width 0.1)
				(type default)
			)
			(layer "B.Fab")
		)
		(fp_line
			(start -0.67945 -0.3048)
			(end -0.67945 0.3048)
			(stroke
				(width 0.1)
				(type default)
			)
			(layer "B.Fab")
		)
		(pad "1" smd circle
			(at 0.40005 0)
			(size 0 0)
			(layers "B.Cu" "B.Mask" "B.Paste")
			(net "PVNN_TERM_CPU0")
		)
		(pad "2" smd circle
			(at -0.40005 0)
			(size 0 0)
			(layers "B.Cu" "B.Mask" "B.Paste")
			(net "FM_PCH_TRIGGER1_R_N")
		)
	)
	(footprint ""
		(layer "B.Cu")
		(at 235.9406 -301.023528)
		(property "Reference" ""
			(at 0 0 0)
			(layer "B.SilkS")
			(hide yes)
			(effects
				(font
					(size 1.27 1.27)
				)
				(justify mirror)
			)
		)
		(property "Value" ""
			(at 0 0 0)
			(layer "B.Fab")
			(effects
				(font
					(size 1.27 1.27)
				)
				(justify mirror)
			)
		)
		(duplicate_pad_numbers_are_jumpers no)
		(pad "1" smd circle
			(at 0 0 180)
			(size 0.9906 0.9906)
			(layers "B.Cu" "B.Mask" "B.Paste")
			(net "Net_293")
		)
		(zone
			(layer "B.Cu")
			(hatch none 0.5)
			(connect_pads
				(clearance 0)
			)
			(min_thickness 0.25)
			(keepout
				(tracks not_allowed)
				(vias allowed)
				(pads allowed)
				(copperpour not_allowed)
				(footprints allowed)
			)
			(placement
				(enabled no)
				(sheetname "")
			)
			(fill
				(thermal_gap 0.5)
				(thermal_bridge_width 0.5)
				(island_removal_mode 0)
			)
			(polygon
				(pts
					(arc
						(start 237.5662 -301.023528)
						(mid 234.315 -301.023528)
						(end 237.5662 -301.023528)
					)
				)
			)
		)
	)
	(footprint ""
		(layer "B.Cu")
		(at 160.935162 -41.832784 90)
		(property "Reference" "R4450"
			(at 0 0 90)
			(layer "B.SilkS")
			(hide yes)
			(effects
				(font
					(size 1.27 1.27)
				)
				(justify mirror)
			)
		)
		(property "Value" ""
			(at 0 0 90)
			(layer "B.Fab")
			(effects
				(font
					(size 1.27 1.27)
				)
				(justify mirror)
			)
		)
		(duplicate_pad_numbers_are_jumpers no)
		(fp_line
			(start 0.7874 -0.4064)
			(end -0.7874 -0.4064)
			(stroke
				(width 0.1524)
				(type default)
			)
			(layer "B.SilkS")
		)
		(fp_line
			(start -0.7874 -0.4064)
			(end -0.7874 0.4064)
			(stroke
				(width 0.1524)
				(type default)
			)
			(layer "B.SilkS")
		)
		(fp_line
			(start 0.7874 0.4064)
			(end 0.7874 -0.4064)
			(stroke
				(width 0.1524)
				(type default)
			)
			(layer "B.SilkS")
		)
		(fp_line
			(start -0.7874 0.4064)
			(end 0.7874 0.4064)
			(stroke
				(width 0.1524)
				(type default)
			)
			(layer "B.SilkS")
		)
		(fp_line
			(start 0.67945 -0.305054)
			(end 0.12065 -0.305054)
			(stroke
				(width 0.1)
				(type default)
			)
			(layer "B.Fab")
		)
		(fp_line
			(start 0.12065 -0.305054)
			(end 0.12065 -0.2794)
			(stroke
				(width 0.1)
				(type default)
			)
			(layer "B.Fab")
		)
		(fp_line
			(start -0.12065 -0.3048)
			(end -0.67945 -0.3048)
			(stroke
				(width 0.1)
				(type default)
			)
			(layer "B.Fab")
		)
		(fp_line
			(start -0.67945 -0.3048)
			(end -0.67945 0.3048)
			(stroke
				(width 0.1)
				(type default)
			)
			(layer "B.Fab")
		)
		(fp_line
			(start 0.12065 -0.2794)
			(end -0.12065 -0.2794)
			(stroke
				(width 0.1)
				(type default)
			)
			(layer "B.Fab")
		)
		(fp_line
			(start -0.12065 -0.2794)
			(end -0.12065 -0.3048)
			(stroke
				(width 0.1)
				(type default)
			)
			(layer "B.Fab")
		)
		(fp_line
			(start 0.12065 0.2794)
			(end 0.12065 0.3048)
			(stroke
				(width 0.1)
				(type default)
			)
			(layer "B.Fab")
		)
		(fp_line
			(start -0.120396 0.2794)
			(end 0.12065 0.2794)
			(stroke
				(width 0.1)
				(type default)
			)
			(layer "B.Fab")
		)
		(fp_line
			(start 0.67945 0.3048)
			(end 0.67945 -0.305054)
			(stroke
				(width 0.1)
				(type default)
			)
			(layer "B.Fab")
		)
		(fp_line
			(start 0.12065 0.3048)
			(end 0.67945 0.3048)
			(stroke
				(width 0.1)
				(type default)
			)
			(layer "B.Fab")
		)
		(fp_line
			(start -0.120396 0.3048)
			(end -0.120396 0.2794)
			(stroke
				(width 0.1)
				(type default)
			)
			(layer "B.Fab")
		)
		(fp_line
			(start -0.67945 0.3048)
			(end -0.120396 0.3048)
			(stroke
				(width 0.1)
				(type default)
			)
			(layer "B.Fab")
		)
		(pad "1" smd circle
			(at 0.40005 0 270)
			(size 0 0)
			(layers "B.Cu" "B.Mask" "B.Paste")
			(net "P3V3_AUX")
		)
		(pad "2" smd circle
			(at -0.40005 0 270)
			(size 0 0)
			(layers "B.Cu" "B.Mask" "B.Paste")
			(net "P3V3_AUX_USB_HUB_2")
		)
	)
)
